FILE_TYPE = MULTI_PHYS_TABLE;

PART 'SCONN3_212H9103GBR1'

{========================================================================================}
:VALUE                   | PART_TYPE | MATERIAL | PART_NUMBER    = STANDARD | LIFECYCLE          | PART_NUMBER   | JEDEC_TYPE          | DESCRIPTION                            | MANUFTR | MANUF_PN         | RD_CMPLS_LVL | CMPLS_LVL | CLASS | DIP_SMD | FROM_PJ      | DATA                     | FP_ECN               | EE_CHECK_LIST | CREATOR | CREATEDAY  | PSL | STATUS | ESD_CDM | ESD_HBM | ESD_MM | MSD  | PIN_LENGTH_LONG_PIN | PIN_LENGTH_SHORT_PIN ;
{========================================================================================}
 'SCONN3_212-H91-03GBR1' | 'SMLF'    | 'IO'     | 'DFHD03MS161'(!) = ''       | ''               | 'DFHD03MS161' |'HEADER1X3SXE_H367'| 'CONN SMD HEADER 3P 1R MS(P2.54,H9.3)' | 'PRX'   | '212-H91-03GBR1' | 'EP(V1)'     | 'EP(V1)'  | 'IO'  | ''      | 'S5C-HOWARD' | 'PRX_212-H91-03GBR1.pdf' | '212-H91-03GBR1.msg' | ''            | ''      | '20200131' | ''  | ''     | 'NA'    | 'NA'    | 'NA'   | 'NA' | '0 MILS'            | '0 MILS'            
 'SCONN3_212-H91-03GBR1' | 'SMLF'    | 'EMPTY'  | 'DFHD03MS161'(!) = ''       | ''               | 'DFHD03MS161' |'HEADER1X3SXE_H367'| 'CONN SMD HEADER 3P 1R MS(P2.54,H9.3)' | 'PRX'   | '212-H91-03GBR1' | 'EP(V1)'     | 'EP(V1)'  | 'IO'  | ''      | 'S5C-HOWARD' | 'PRX_212-H91-03GBR1.pdf' | '212-H91-03GBR1.msg' | ''            | ''      | '20200131' | ''  | ''     | 'NA'    | 'NA'    | 'NA'   | 'NA' | '0 MILS'            | '0 MILS'            

END_PART

END.

